FILE_TYPE = CONNECTIVITY;
{Allegro Design Entry HDL 17.4-2019 S026 (4007227) 1/17/2022}
"PAGE_NUMBER" = 365;
0"NC";
1"P12V_AUX\g";
2"GND\g";
3"GND\g";
4"GND\g";
5"P3V3_AUX\g";
6"P3V3_AUX\g";
7"GND\g";
8"P12V_AUX\g";
9"P12V_AUX_BLEEDING";
10"FM_P12V_HSC_EN_R_N";
11"FM_P12V_HSC_EN_N";
12"MB0_P12V_STBY_PWRGD";
13"FM_P12V_HSC_EN_R";
14"FM_AC_PWR_BTN_PLD_N";
15"FM_AC_PWR_BTN_R_N";
16"FM_AC_PWR_BTN_PLD_ISO_R_N";
17"NC_U8004_2Y";
18"P3V3_AUX\g";
19"GND\g";
20"FM_AC_PWR_BTN_PLD_ISO_N";
%"Q_RES"
"2","(14600,4050)","0","pure_quanta","I10";
;
LOCATION"R2530"
$SEC"1"
CDS_SEC"1"
WATTAGE"1/16W"
MATERIAL"CHIP"
PACK_TYPE"0402LF"
TOLERANCE"5%"
VALUE"4.7K"
CDS_LIB"pure_quanta"
PART_NUMBER"CS24702JB10";
"A"
$PN"1"1;
"B"
$PN"2"9;
%"UNIVERSAL_POWER"
"1","(14600,4300)","0","pure_quanta_power","I11";
;
HDL_POWER"P12V_AUX"
CDS_LIB"pure_quanta_power";
"A"1;
%"MOSFET_NCH_GDS_ESD_PROTECTED"
"1","(14000,3450)","0","pure_quanta","I14";
;
LOCATION"Q54"
$SEC"1"
CDS_SEC"1"
PART_TYPE"SMLF"
VALUE"2N7002K"
MATERIAL"IC"
NEEDS_NO_SIZE"TRUE"
CDS_LMAN_SYM_OUTLINE"-125,150,125,-150"
CDS_LIB"pure_quanta"
PART_NUMBER"BAM70020002";
"S"
$PN"S"2;
"G"
$PN"G"10;
"D"
$PN"D"9;
%"UNIVERSAL_GND"
"1","(14025,3050)","0","pure_quanta_power","I15";
;
CDS_LIB"pure_quanta_power"
HDL_POWER"GND";
"A"2;
%"74LVC2G07DW7"
"1","(11550,1350)","0","pure_quanta","I16";
;
LOCATION"U8004"
SEC"1"
VALUE"74LVC2G07DW-7"
MATERIAL"EMPTY"
PART_TYPE"SMLF"
SEC_TYPE""
CDS_LIB"pure_quanta"
NEEDS_NO_SIZE"TRUE"
CDS_LMAN_SYM_OUTLINE"-175,100,175,-100"
PART_NUMBER"AL002G07003";
"VCC"
$PN"5"18;
"GND"
$PN"2"19;
"2Y"
$PN"4"17;
"1Y"
$PN"6"16;
"2A"
$PN"3"19;
"1A"
$PN"1"14;
%"UNIVERSAL_GND"
"1","(11150,1200)","0","pure_quanta_power","I17";
;
CDS_LIB"pure_quanta_power"
HDL_POWER"GND";
"A"19;
%"Q_RES"
"1","(9975,1400)","0","pure_quanta","I18";
;
LOCATION"R8104"
$SEC"1"
CDS_SEC"1"
PACK_TYPE"0402LF"
TOLERANCE"5%"
MATERIAL"EMPTY"
VALUE"0"
WATTAGE"1/16W"
CDS_LIB"pure_quanta"
PART_NUMBER"CS00002JB13";
"B"
$PN"2"14;
"A"
$PN"1"15;
%"Q_RES"
"1","(13875,1400)","0","pure_quanta","I20";
;
LOCATION"R8105"
$SEC"1"
CDS_SEC"1"
VALUE"0"
TOLERANCE"5%"
WATTAGE"1/16W"
MATERIAL"EMPTY"
PACK_TYPE"0402LF"
CDS_LIB"pure_quanta"
PART_NUMBER"CS00002JB13";
"B"
$PN"2"20;
"A"
$PN"1"16;
%"UNIVERSAL_POWER"
"1","(12200,2375)","0","pure_quanta_power","I22";
;
HDL_POWER"P3V3_AUX"
CDS_LIB"pure_quanta_power";
"A"18;
%"Q_CAP"
"1","(12400,2050)","0","pure_quanta","I23";
;
LOCATION"C8013"
$SEC"1"
CDS_SEC"1"
VOLTAGE"25V"
PACK_TYPE"0402"
MATERIAL"EMPTY"
TOLERANCE"10%"
VALUE"0.1UF"
CDS_LIB"pure_quanta"
PART_NUMBER"CH4104K1B00";
"B"
$PN"2"3;
"A"
$PN"1"18;
%"UNIVERSAL_GND"
"1","(12400,1750)","0","pure_quanta_power","I24";
;
CDS_LIB"pure_quanta_power"
HDL_POWER"GND";
"A"3;
%"Q_CAP"
"1","(9450,900)","0","pure_quanta","I25";
;
LOCATION"C8012"
$SEC"1"
CDS_SEC"1"
VALUE"1UF"
PACK_TYPE"C0402"
MATERIAL"EMPTY"
TOLERANCE"10%"
VOLTAGE"25V"
CDS_LIB"pure_quanta"
PART_NUMBER"CH5104KEB02";
"B"
$PN"2"4;
"A"
$PN"1"15;
%"UNIVERSAL_GND"
"1","(9450,450)","0","pure_quanta_power","I26";
;
CDS_LIB"pure_quanta_power"
HDL_POWER"GND";
"A"4;
%"Q_RES"
"2","(9375,1900)","0","pure_quanta","I27";
;
LOCATION"R8103"
$SEC"1"
CDS_SEC"1"
WATTAGE"1/16W"
PACK_TYPE"0402LF"
MATERIAL"EMPTY"
TOLERANCE"1%"
VALUE"8.45K"
CDS_LIB"pure_quanta"
PART_NUMBER"CS28452FB06";
"A"
$PN"1"5;
"B"
$PN"2"15;
%"UNIVERSAL_POWER"
"1","(9375,2300)","0","pure_quanta_power","I28";
;
HDL_POWER"P3V3_AUX"
CDS_LIB"pure_quanta_power";
"A"5;
%"Q_RES"
"1","(10325,3125)","0","pure_quanta","I3";
;
LOCATION"R2531"
$SEC"1"
CDS_SEC"1"
VALUE"0"
MATERIAL"CHIP"
TOLERANCE"5%"
WATTAGE"1/16W"
PACK_TYPE"0402LF"
CDS_LIB"pure_quanta"
PART_NUMBER"CS00002JB13";
"B"
$PN"2"13;
"A"
$PN"1"12;
%"UNIVERSAL_POWER"
"1","(14500,2400)","0","pure_quanta_power","I30";
;
HDL_POWER"P3V3_AUX"
CDS_LIB"pure_quanta_power";
"A"6;
%"Q_RES"
"2","(14500,2050)","0","pure_quanta","I31";
;
LOCATION"R8106"
$SEC"1"
CDS_SEC"1"
VALUE"1K"
TOLERANCE"1%"
WATTAGE"1/16W"
PACK_TYPE"0402LF"
MATERIAL"CHIP"
CDS_LIB"pure_quanta"
PART_NUMBER"CS21002FB06";
"A"
$PN"1"6;
"B"
$PN"2"20;
%"UNIVERSAL_GND"
"1","(11650,2775)","0","pure_quanta_power","I5";
;
CDS_LIB"pure_quanta_power"
HDL_POWER"GND";
"A"7;
%"MOSFET_NCH_GDS_ESD_PROTECTED"
"1","(11625,3125)","0","pure_quanta","I6";
;
LOCATION"U158"
$SEC"1"
CDS_SEC"1"
PART_TYPE"SMLF"
MATERIAL"IC"
VALUE"2N7002K"
CDS_LIB"pure_quanta"
CDS_LMAN_SYM_OUTLINE"-125,150,125,-150"
NEEDS_NO_SIZE"TRUE"
PART_NUMBER"BAM70020002";
"S"
$PN"S"7;
"G"
$PN"G"13;
"D"
$PN"D"11;
%"Q_RES"
"1","(12575,3450)","0","pure_quanta","I7";
;
LOCATION"R2529"
$SEC"1"
CDS_SEC"1"
TOLERANCE"5%"
VALUE"0"
WATTAGE"1/16W"
PACK_TYPE"0402LF"
MATERIAL"CHIP"
CDS_LIB"pure_quanta"
PART_NUMBER"CS00002JB13";
"B"
$PN"2"10;
"A"
$PN"1"11;
%"Q_RES"
"2","(11650,3850)","0","pure_quanta","I8";
;
LOCATION"R2528"
$SEC"1"
CDS_SEC"1"
PACK_TYPE"0402LF"
VALUE"100K"
TOLERANCE"1%"
MATERIAL"CHIP"
WATTAGE"1/16W"
CDS_LIB"pure_quanta"
PART_NUMBER"CS41002FB09";
"A"
$PN"1"8;
"B"
$PN"2"11;
%"UNIVERSAL_POWER"
"1","(11650,4100)","0","pure_quanta_power","I9";
;
HDL_POWER"P12V_AUX"
CDS_LIB"pure_quanta_power";
"A"8;
END.
